FILE_TYPE = CONNECTIVITY;
{Allegro Design Entry HDL 17.2-2016 S081 (4005846) 1/11/2022}
"PAGE_NUMBER" = 138;
0"NC";
END.
